# T6G (Grand Teton) — schematic netlist excerpt (pin names and nets, part order shuffled) for the footprints in the layout excerpt that follows; sources: Cadence DE-HDL packaged netlist, KiCad conversion of 04192023_DAF0TMB3IC0_F0TG_MB_C_brd_V02_OCP.brd

C2219  Q_CAP  22UF 4V 20% X6S  pkg C0402  page 69 : A = PVDDCR_CPU1_P0 ; B = GND
C801  Q_CAP  100UF 4V 20% X6S  pkg C0805  page 301 : A = P0V9_CPU0_RT_2D ; B = GND
C1048  Q_CAP  0.1UF 10V 10% X7S  pkg C0201  page 312 : A = P0V9_CPU0_RT_2D ; B = GND
C781  Q_CAP  1UF 4V 20% X6S  pkg 0201  page 301 : A = P0V9_CPU0_RT2_2A ; B = GND

(kicad_pcb
	(version 20260206)
	(generator "pcbnew")
	(generator_version "10.0")
	(general
		(thickness 1.6)
		(legacy_teardrops no)
	)
	(paper "A4")
	(title_block
		(title "04192023_DAF0TMB3IC0_F0TG_MB_C_brd_V02_OCP.brd")
		(comment 1 "Grand Teton / footprints 5457-5460 of 8354")
	)
	(layers
		(0 "F.Cu" signal "TOP")
		(4 "In1.Cu" signal "GND")
		(6 "In2.Cu" signal "IN1")
		(8 "In3.Cu" signal "GND1")
		(10 "In4.Cu" signal "IN2")
		(12 "In5.Cu" signal "GND2")
		(14 "In6.Cu" signal "IN3")
		(16 "In7.Cu" signal "GND3")
		(18 "In8.Cu" signal "VCC")
		(20 "In9.Cu" signal "VCC1")
		(22 "In10.Cu" signal "GND4")
		(24 "In11.Cu" signal "IN4")
		(26 "In12.Cu" signal "GND5")
		(28 "In13.Cu" signal "IN5")
		(30 "In14.Cu" signal "GND6")
		(32 "In15.Cu" signal "IN6")
		(34 "In16.Cu" signal "GND7")
		(2 "B.Cu" signal "BOTTOM")
		(9 "F.Adhes" user "F.Adhesive")
		(11 "B.Adhes" user "B.Adhesive")
		(13 "F.Paste" user "Package Geometry/Pastemask Top")
		(15 "B.Paste" user "Package Geometry/Pastemask Bottom")
		(5 "F.SilkS" user "Ref Des/Silkscreen Top")
		(7 "B.SilkS" user "Ref Des/Silkscreen Bottom")
		(1 "F.Mask" user "Board Geometry/Soldermask Top")
		(3 "B.Mask" user "Board Geometry/Soldermask Bottom")
		(17 "Dwgs.User" user "User.Drawings")
		(19 "Cmts.User" user "User.Comments")
		(21 "Eco1.User" user "User.Eco1")
		(23 "Eco2.User" user "User.Eco2")
		(25 "Edge.Cuts" user "Board Geometry/Outline")
		(27 "Margin" user)
		(31 "F.CrtYd" user "Package Geometry/Place Bound Top")
		(29 "B.CrtYd" user "Package Geometry/Place Bound Bottom")
		(35 "F.Fab" user "Ref Des/Assembly Top")
		(33 "B.Fab" user "Ref Des/Assembly Bottom")
	)
	(footprint ""
		(layer "B.Cu")
		(at 382.478534 -395.148562 90)
		(property "Reference" "C1048"
			(at 0 0 90)
			(layer "B.SilkS")
			(hide yes)
			(effects
				(font
					(size 1.27 1.27)
				)
				(justify mirror)
			)
		)
		(property "Value" ""
			(at 0 0 90)
			(layer "B.Fab")
			(effects
				(font
					(size 1.27 1.27)
				)
				(justify mirror)
			)
		)
		(duplicate_pad_numbers_are_jumpers no)
		(fp_line
			(start 0.299974 -0.150114)
			(end -0.299974 -0.150114)
			(stroke
				(width 0.1)
				(type default)
			)
			(layer "B.Fab")
		)
		(fp_line
			(start -0.299974 -0.150114)
			(end -0.299974 0.150114)
			(stroke
				(width 0.1)
				(type default)
			)
			(layer "B.Fab")
		)
		(fp_line
			(start 0.299974 0.150114)
			(end 0.299974 -0.150114)
			(stroke
				(width 0.1)
				(type default)
			)
			(layer "B.Fab")
		)
		(fp_line
			(start -0.299974 0.150114)
			(end 0.299974 0.150114)
			(stroke
				(width 0.1)
				(type default)
			)
			(layer "B.Fab")
		)
		(pad "1" smd rect
			(at 0.2667 0 270)
			(size 0.3048 0.381)
			(layers "B.Cu" "B.Mask" "B.Paste")
			(net "P0V9_CPU0_RT_2D")
		)
		(pad "2" smd rect
			(at -0.2667 0 270)
			(size 0.3048 0.381)
			(layers "B.Cu" "B.Mask" "B.Paste")
			(net "GND")
		)
	)
	(footprint ""
		(layer "B.Cu")
		(at 401.046188 -395.43228)
		(property "Reference" "C781"
			(at 0 0 0)
			(layer "B.SilkS")
			(hide yes)
			(effects
				(font
					(size 1.27 1.27)
				)
				(justify mirror)
			)
		)
		(property "Value" ""
			(at 0 0 0)
			(layer "B.Fab")
			(effects
				(font
					(size 1.27 1.27)
				)
				(justify mirror)
			)
		)
		(duplicate_pad_numbers_are_jumpers no)
		(fp_line
			(start -0.299974 -0.150114)
			(end -0.299974 0.150114)
			(stroke
				(width 0.1)
				(type default)
			)
			(layer "B.Fab")
		)
		(fp_line
			(start -0.299974 0.150114)
			(end 0.299974 0.150114)
			(stroke
				(width 0.1)
				(type default)
			)
			(layer "B.Fab")
		)
		(fp_line
			(start 0.299974 -0.150114)
			(end -0.299974 -0.150114)
			(stroke
				(width 0.1)
				(type default)
			)
			(layer "B.Fab")
		)
		(fp_line
			(start 0.299974 0.150114)
			(end 0.299974 -0.150114)
			(stroke
				(width 0.1)
				(type default)
			)
			(layer "B.Fab")
		)
		(pad "1" smd rect
			(at 0.2667 0 180)
			(size 0.3048 0.381)
			(layers "B.Cu" "B.Mask" "B.Paste")
			(net "P0V9_CPU0_RT2_2A")
		)
		(pad "2" smd rect
			(at -0.2667 0 180)
			(size 0.3048 0.381)
			(layers "B.Cu" "B.Mask" "B.Paste")
			(net "GND")
		)
	)
	(footprint ""
		(layer "B.Cu")
		(at 364.312454 -268.41831)
		(property "Reference" "C2219"
			(at 0 0 0)
			(layer "B.SilkS")
			(hide yes)
			(effects
				(font
					(size 1.27 1.27)
				)
				(justify mirror)
			)
		)
		(property "Value" ""
			(at 0 0 0)
			(layer "B.Fab")
			(effects
				(font
					(size 1.27 1.27)
				)
				(justify mirror)
			)
		)
		(duplicate_pad_numbers_are_jumpers no)
		(fp_line
			(start -0.7874 -0.4064)
			(end -0.7874 0.4064)
			(stroke
				(width 0.1524)
				(type default)
			)
			(layer "B.SilkS")
		)
		(fp_line
			(start -0.7874 0.4064)
			(end 0.7874 0.4064)
			(stroke
				(width 0.1524)
				(type default)
			)
			(layer "B.SilkS")
		)
		(fp_line
			(start 0.7874 -0.4064)
			(end -0.7874 -0.4064)
			(stroke
				(width 0.1524)
				(type default)
			)
			(layer "B.SilkS")
		)
		(fp_line
			(start 0.7874 0.4064)
			(end 0.7874 -0.4064)
			(stroke
				(width 0.1524)
				(type default)
			)
			(layer "B.SilkS")
		)
		(fp_line
			(start -0.67945 -0.3048)
			(end -0.67945 0.3048)
			(stroke
				(width 0.1)
				(type default)
			)
			(layer "B.Fab")
		)
		(fp_line
			(start -0.67945 0.3048)
			(end -0.120396 0.3048)
			(stroke
				(width 0.1)
				(type default)
			)
			(layer "B.Fab")
		)
		(fp_line
			(start -0.12065 -0.3048)
			(end -0.67945 -0.3048)
			(stroke
				(width 0.1)
				(type default)
			)
			(layer "B.Fab")
		)
		(fp_line
			(start -0.12065 -0.2794)
			(end -0.12065 -0.3048)
			(stroke
				(width 0.1)
				(type default)
			)
			(layer "B.Fab")
		)
		(fp_line
			(start -0.120396 0.2794)
			(end 0.12065 0.2794)
			(stroke
				(width 0.1)
				(type default)
			)
			(layer "B.Fab")
		)
		(fp_line
			(start -0.120396 0.3048)
			(end -0.120396 0.2794)
			(stroke
				(width 0.1)
				(type default)
			)
			(layer "B.Fab")
		)
		(fp_line
			(start 0.12065 -0.305054)
			(end 0.12065 -0.2794)
			(stroke
				(width 0.1)
				(type default)
			)
			(layer "B.Fab")
		)
		(fp_line
			(start 0.12065 -0.2794)
			(end -0.12065 -0.2794)
			(stroke
				(width 0.1)
				(type default)
			)
			(layer "B.Fab")
		)
		(fp_line
			(start 0.12065 0.2794)
			(end 0.12065 0.3048)
			(stroke
				(width 0.1)
				(type default)
			)
			(layer "B.Fab")
		)
		(fp_line
			(start 0.12065 0.3048)
			(end 0.67945 0.3048)
			(stroke
				(width 0.1)
				(type default)
			)
			(layer "B.Fab")
		)
		(fp_line
			(start 0.67945 -0.305054)
			(end 0.12065 -0.305054)
			(stroke
				(width 0.1)
				(type default)
			)
			(layer "B.Fab")
		)
		(fp_line
			(start 0.67945 0.3048)
			(end 0.67945 -0.305054)
			(stroke
				(width 0.1)
				(type default)
			)
			(layer "B.Fab")
		)
		(pad "1" smd circle
			(at 0.40005 0 180)
			(size 0 0)
			(layers "B.Cu" "B.Mask" "B.Paste")
			(net "PVDDCR_CPU1_P0")
		)
		(pad "2" smd circle
			(at -0.40005 0 180)
			(size 0 0)
			(layers "B.Cu" "B.Mask" "B.Paste")
			(net "GND")
		)
	)
	(footprint ""
		(layer "B.Cu")
		(at 395.562582 -398.055084 90)
		(property "Reference" "C801"
			(at 0 0 90)
			(layer "B.SilkS")
			(hide yes)
			(effects
				(font
					(size 1.27 1.27)
				)
				(justify mirror)
			)
		)
		(property "Value" ""
			(at 0 0 90)
			(layer "B.Fab")
			(effects
				(font
					(size 1.27 1.27)
				)
				(justify mirror)
			)
		)
		(duplicate_pad_numbers_are_jumpers no)
		(fp_line
			(start 1.524 -0.762)
			(end -1.524 -0.762)
			(stroke
				(width 0.1524)
				(type default)
			)
			(layer "B.SilkS")
		)
		(fp_line
			(start -1.524 -0.762)
			(end -1.524 0.762)
			(stroke
				(width 0.1524)
				(type default)
			)
			(layer "B.SilkS")
		)
		(fp_line
			(start 1.524 0.762)
			(end 1.524 -0.762)
			(stroke
				(width 0.1524)
				(type default)
			)
			(layer "B.SilkS")
		)
		(fp_line
			(start -1.524 0.762)
			(end 1.524 0.762)
			(stroke
				(width 0.1524)
				(type default)
			)
			(layer "B.SilkS")
		)
		(fp_line
			(start 1.1049 -0.724916)
			(end 1.1049 0.724916)
			(stroke
				(width 0.1)
				(type default)
			)
			(layer "B.Fab")
		)
		(fp_line
			(start -1.1049 -0.724916)
			(end 1.1049 -0.724916)
			(stroke
				(width 0.1)
				(type default)
			)
			(layer "B.Fab")
		)
		(fp_line
			(start 1.1049 0.724916)
			(end -1.1049 0.724916)
			(stroke
				(width 0.1)
				(type default)
			)
			(layer "B.Fab")
		)
		(fp_line
			(start -1.1049 0.724916)
			(end -1.1049 -0.724916)
			(stroke
				(width 0.1)
				(type default)
			)
			(layer "B.Fab")
		)
		(pad "1" smd rect
			(at 0.889 0 90)
			(size 1.016 1.27)
			(layers "B.Cu" "B.Mask" "B.Paste")
			(net "P0V9_CPU0_RT_2D")
		)
		(pad "2" smd rect
			(at -0.889 0 90)
			(size 1.016 1.27)
			(layers "B.Cu" "B.Mask" "B.Paste")
			(net "GND")
		)
	)
)
